(kicad_pcb
	(version 20241229)
	(generator "pcbnew")
	(generator_version "9.0")
	(general
		(thickness 1.599998)
		(legacy_teardrops no)
	)
	(paper "A4")
	(title_block
		(date "2023-02-12")
		(rev "1.1.5")
		(comment 9 "footprints 196-202 of 473")
	)
	(layers
		(0 "F.Cu" signal)
		(4 "In1.Cu" power "In1.GND")
		(6 "In2.Cu" signal)
		(8 "In3.Cu" power "In3.GND")
		(10 "In4.Cu" power "In4.VCC")
		(12 "In5.Cu" signal)
		(14 "In6.Cu" power "In6.VCC")
		(2 "B.Cu" signal)
		(9 "F.Adhes" user "F.Adhesive")
		(11 "B.Adhes" user "B.Adhesive")
		(13 "F.Paste" user)
		(15 "B.Paste" user)
		(5 "F.SilkS" user "F.Silkscreen")
		(7 "B.SilkS" user "B.Silkscreen")
		(1 "F.Mask" user)
		(3 "B.Mask" user)
		(17 "Dwgs.User" user "User.Drawings")
		(19 "Cmts.User" user "User.Comments")
		(21 "Eco1.User" user "User.Eco1")
		(23 "Eco2.User" user "User.Eco2")
		(25 "Edge.Cuts" user)
		(27 "Margin" user)
		(31 "F.CrtYd" user "F.Courtyard")
		(29 "B.CrtYd" user "B.Courtyard")
		(35 "F.Fab" user)
		(33 "B.Fab" user)
	)
	(footprint "antmicro-footprints:L_WE-MAIA-3015"
		(layer "F.Cu")
		(at 126.29 84.374 180)
		(property "Reference" "L4"
			(at -1.98 0.554 0)
			(unlocked yes)
			(layer "F.SilkS")
			(effects
				(font
					(size 0.7 0.7)
					(thickness 0.15)
				)
				(justify left bottom)
			)
		)
		(property "Value" "784383350047"
			(at -1.9 2.7 180)
			(unlocked yes)
			(layer "F.Fab")
			(effects
				(font
					(size 0.7 0.7)
					(thickness 0.15)
				)
				(justify left bottom)
			)
		)
		(property "Description" "Power Inductor (SMT), AEC-Q200, 470 nH, 4.6 A, Shielded, 5.8 A, WE-MAIA"
			(at 0 0 180)
			(layer "F.Fab")
			(hide yes)
			(effects
				(font
					(size 1.27 1.27)
					(thickness 0.15)
				)
			)
		)
		(property "Author" "Antmicro"
			(at 252.58 168.748 0)
			(layer "F.Fab")
			(hide yes)
			(effects
				(font
					(size 1 1)
					(thickness 0.15)
				)
			)
		)
		(property "IMax" "4.6 A"
			(at 252.58 168.748 0)
			(layer "F.Fab")
			(hide yes)
			(effects
				(font
					(size 1 1)
					(thickness 0.15)
				)
			)
		)
		(property "ISat" "5.8 A"
			(at 252.58 168.748 0)
			(layer "F.Fab")
			(hide yes)
			(effects
				(font
					(size 1 1)
					(thickness 0.15)
				)
			)
		)
		(property "License" "Apache-2.0"
			(at 252.58 168.748 0)
			(layer "F.Fab")
			(hide yes)
			(effects
				(font
					(size 1 1)
					(thickness 0.15)
				)
			)
		)
		(property "MPN" "784383350047"
			(at 252.58 168.748 0)
			(layer "F.Fab")
			(hide yes)
			(effects
				(font
					(size 1 1)
					(thickness 0.15)
				)
			)
		)
		(property "Manufacturer" "Würth Elektronik"
			(at 252.58 168.748 0)
			(layer "F.Fab")
			(hide yes)
			(effects
				(font
					(size 1 1)
					(thickness 0.15)
				)
			)
		)
		(property "Size" "3.0x3.0"
			(at 252.58 168.748 0)
			(layer "F.Fab")
			(hide yes)
			(effects
				(font
					(size 1 1)
					(thickness 0.15)
				)
			)
		)
		(property "Val" "470n/4.6A"
			(at 252.58 168.748 0)
			(layer "F.Fab")
			(hide yes)
			(effects
				(font
					(size 1 1)
					(thickness 0.15)
				)
			)
		)
		(sheetname "Supply")
		(sheetfile "supply.kicad_sch")
		(attr smd)
		(fp_line
			(start -0.175 1.625)
			(end 0.175 1.625)
			(stroke
				(width 0.15)
				(type solid)
			)
			(layer "F.SilkS")
		)
		(fp_line
			(start -0.175 -1.625)
			(end 0.175 -1.625)
			(stroke
				(width 0.15)
				(type solid)
			)
			(layer "F.SilkS")
		)
		(fp_rect
			(start -1.95 -1.95)
			(end 1.95 1.95)
			(stroke
				(width 0.05)
				(type solid)
			)
			(fill no)
			(layer "F.CrtYd")
		)
		(fp_rect
			(start -1.5 -1.5)
			(end 1.5 1.5)
			(stroke
				(width 0.15)
				(type solid)
			)
			(fill no)
			(layer "F.Fab")
		)
		(pad "1" smd roundrect
			(at -1.05 0 180)
			(size 1.3 3.4)
			(layers "F.Cu" "F.Mask" "F.Paste")
			(roundrect_rratio 0.1)
			(net 579 "/Supply/1V1_SW")
			(pintype "passive")
		)
		(pad "2" smd roundrect
			(at 1.05 0 180)
			(size 1.3 3.4)
			(layers "F.Cu" "F.Mask" "F.Paste")
			(roundrect_rratio 0.1)
			(net 587 "/Supply/1V1_REG")
			(pintype "passive")
		)
	)
	(footprint "antmicro-footprints:C_0402_1005Metric"
		(layer "F.Cu")
		(at 127.6825 98.299)
		(descr "Capacitor SMD 0402")
		(tags "capacitor SMD 0402")
		(property "Reference" "C161"
			(at -3.5825 0.401 0)
			(layer "F.SilkS")
			(effects
				(font
					(size 0.7 0.7)
					(thickness 0.15)
				)
				(justify left bottom)
			)
		)
		(property "Value" "C_100n_6V3_0402"
			(at 0 1.4 0)
			(layer "F.Fab")
			(effects
				(font
					(size 0.7 0.7)
					(thickness 0.15)
				)
				(justify left bottom)
			)
		)
		(property "Description" " "
			(at 0 0 0)
			(layer "F.Fab")
			(hide yes)
			(effects
				(font
					(size 1.27 1.27)
					(thickness 0.15)
				)
			)
		)
		(property "Author" "Antmicro"
			(at 0 0 0)
			(layer "F.Fab")
			(hide yes)
			(effects
				(font
					(size 1 1)
					(thickness 0.15)
				)
			)
		)
		(property "Dielectric" ""
			(at 0 0 0)
			(layer "F.Fab")
			(hide yes)
			(effects
				(font
					(size 1 1)
					(thickness 0.15)
				)
			)
		)
		(property "License" "Apache-2.0"
			(at 0 0 0)
			(layer "F.Fab")
			(hide yes)
			(effects
				(font
					(size 1 1)
					(thickness 0.15)
				)
			)
		)
		(property "MPN" "0402X104K6R3CT"
			(at 0 0 0)
			(layer "F.Fab")
			(hide yes)
			(effects
				(font
					(size 1 1)
					(thickness 0.15)
				)
			)
		)
		(property "Manufacturer" "Walsin"
			(at 0 0 0)
			(layer "F.Fab")
			(hide yes)
			(effects
				(font
					(size 1 1)
					(thickness 0.15)
				)
			)
		)
		(property "Val" "100n"
			(at 0 0 0)
			(layer "F.Fab")
			(hide yes)
			(effects
				(font
					(size 1 1)
					(thickness 0.15)
				)
			)
		)
		(property "Voltage" ""
			(at 0 0 0)
			(layer "F.Fab")
			(hide yes)
			(effects
				(font
					(size 1 1)
					(thickness 0.15)
				)
			)
		)
		(sheetname "Supply")
		(sheetfile "supply.kicad_sch")
		(attr smd)
		(fp_rect
			(start -0.94 -0.47)
			(end 0.94 0.47)
			(stroke
				(width 0.05)
				(type solid)
			)
			(fill no)
			(layer "F.CrtYd")
		)
		(fp_rect
			(start -0.499 -0.249)
			(end 0.499 0.249)
			(stroke
				(width 0.15)
				(type solid)
			)
			(fill no)
			(layer "F.Fab")
		)
		(pad "1" smd roundrect
			(at -0.484 0)
			(size 0.59 0.64)
			(layers "F.Cu" "F.Mask" "F.Paste")
			(roundrect_rratio 0.25)
			(net 582 "/Supply/1V0_SW")
			(pintype "passive")
		)
		(pad "2" smd roundrect
			(at 0.484 0)
			(size 0.59 0.64)
			(layers "F.Cu" "F.Mask" "F.Paste")
			(roundrect_rratio 0.25)
			(net 581 "/Supply/1V0_BST")
			(pintype "passive")
		)
	)
	(footprint "lpddr4-test-board-footprints:mounting-hole-3.2mm"
		(layer "F.Cu")
		(at 110.0492 132.9)
		(property "Reference" "MH4"
			(at -0.178 4.025 0)
			(layer "F.SilkS")
			(hide yes)
			(effects
				(font
					(size 0.7 0.7)
					(thickness 0.15)
				)
				(justify left bottom)
			)
		)
		(property "Value" "M3.2"
			(at -0.153 -4.153 0)
			(layer "F.Fab")
			(effects
				(font
					(size 0.7 0.7)
					(thickness 0.15)
				)
				(justify left bottom)
			)
		)
		(attr through_hole board_only exclude_from_bom)
		(pad "1" thru_hole circle
			(at 0 0)
			(size 6 6)
			(drill 3.2)
			(layers "*.Cu" "*.Mask")
			(remove_unused_layers no)
		)
	)
	(footprint "antmicro-footprints:C_0402_1005Metric"
		(layer "F.Cu")
		(at 123.14 85.724 180)
		(descr "Capacitor SMD 0402")
		(tags "capacitor SMD 0402")
		(property "Reference" "C174"
			(at 1.94 2.524 180)
			(layer "F.SilkS")
			(effects
				(font
					(size 0.7 0.7)
					(thickness 0.15)
				)
				(justify left bottom)
			)
		)
		(property "Value" "C_22u_0402"
			(at 0 1.4 180)
			(layer "F.Fab")
			(effects
				(font
					(size 0.7 0.7)
					(thickness 0.15)
				)
				(justify left bottom)
			)
		)
		(property "Description" " "
			(at 0 0 180)
			(layer "F.Fab")
			(hide yes)
			(effects
				(font
					(size 1.27 1.27)
					(thickness 0.15)
				)
			)
		)
		(property "Author" "Antmicro"
			(at 246.28 171.448 0)
			(layer "F.Fab")
			(hide yes)
			(effects
				(font
					(size 1 1)
					(thickness 0.15)
				)
			)
		)
		(property "Dielectric" ""
			(at 246.28 171.448 0)
			(layer "F.Fab")
			(hide yes)
			(effects
				(font
					(size 1 1)
					(thickness 0.15)
				)
			)
		)
		(property "License" "Apache-2.0"
			(at 246.28 171.448 0)
			(layer "F.Fab")
			(hide yes)
			(effects
				(font
					(size 1 1)
					(thickness 0.15)
				)
			)
		)
		(property "MPN" "04024W226MAT2A"
			(at 246.28 171.448 0)
			(layer "F.Fab")
			(hide yes)
			(effects
				(font
					(size 1 1)
					(thickness 0.15)
				)
			)
		)
		(property "Manufacturer" "AVX"
			(at 246.28 171.448 0)
			(layer "F.Fab")
			(hide yes)
			(effects
				(font
					(size 1 1)
					(thickness 0.15)
				)
			)
		)
		(property "Val" "22u"
			(at 246.28 171.448 0)
			(layer "F.Fab")
			(hide yes)
			(effects
				(font
					(size 1 1)
					(thickness 0.15)
				)
			)
		)
		(property "Voltage" ""
			(at 246.28 171.448 0)
			(layer "F.Fab")
			(hide yes)
			(effects
				(font
					(size 1 1)
					(thickness 0.15)
				)
			)
		)
		(sheetname "Supply")
		(sheetfile "supply.kicad_sch")
		(attr smd)
		(fp_rect
			(start -0.94 -0.47)
			(end 0.94 0.47)
			(stroke
				(width 0.05)
				(type solid)
			)
			(fill no)
			(layer "F.CrtYd")
		)
		(fp_rect
			(start -0.499 -0.249)
			(end 0.499 0.249)
			(stroke
				(width 0.15)
				(type solid)
			)
			(fill no)
			(layer "F.Fab")
		)
		(pad "1" smd roundrect
			(at -0.484 0 180)
			(size 0.59 0.64)
			(layers "F.Cu" "F.Mask" "F.Paste")
			(roundrect_rratio 0.25)
			(net 587 "/Supply/1V1_REG")
			(pintype "passive")
		)
		(pad "2" smd roundrect
			(at 0.484 0 180)
			(size 0.59 0.64)
			(layers "F.Cu" "F.Mask" "F.Paste")
			(roundrect_rratio 0.25)
			(net 5 "GND")
			(pintype "passive")
		)
	)
	(footprint "antmicro-footprints:SOT-523"
		(layer "F.Cu")
		(at 142.3825 92.099 90)
		(property "Reference" "Q9"
			(at 0.599 -1.9825 0)
			(layer "F.SilkS")
			(effects
				(font
					(size 0.7 0.7)
					(thickness 0.15)
				)
				(justify left bottom)
			)
		)
		(property "Value" "DMG1012T-7"
			(at 0.1 1.824 90)
			(layer "F.Fab")
			(effects
				(font
					(size 0.7 0.7)
					(thickness 0.15)
				)
				(justify left bottom)
			)
		)
		(property "Author" "Antmicro"
			(at 234.4815 -50.2835 0)
			(layer "F.Fab")
			(hide yes)
			(effects
				(font
					(size 1 1)
					(thickness 0.15)
				)
			)
		)
		(property "License" "Apache-2.0"
			(at 234.4815 -50.2835 0)
			(layer "F.Fab")
			(hide yes)
			(effects
				(font
					(size 1 1)
					(thickness 0.15)
				)
			)
		)
		(property "MPN" "DMG1012T-7"
			(at 234.4815 -50.2835 0)
			(layer "F.Fab")
			(hide yes)
			(effects
				(font
					(size 1 1)
					(thickness 0.15)
				)
			)
		)
		(property "Manufacturer" "Diodes Incorporated"
			(at 234.4815 -50.2835 0)
			(layer "F.Fab")
			(hide yes)
			(effects
				(font
					(size 1 1)
					(thickness 0.15)
				)
			)
		)
		(sheetname "Supply")
		(sheetfile "supply.kicad_sch")
		(attr smd)
		(fp_line
			(start -0.277 -0.551)
			(end -0.277 -0.75)
			(stroke
				(width 0.15)
				(type solid)
			)
			(layer "F.SilkS")
		)
		(fp_line
			(start -0.725 -0.551)
			(end -0.277 -0.551)
			(stroke
				(width 0.15)
				(type solid)
			)
			(layer "F.SilkS")
		)
		(fp_line
			(start -0.927 -0.351)
			(end -0.725 -0.551)
			(stroke
				(width 0.15)
				(type solid)
			)
			(layer "F.SilkS")
		)
		(fp_line
			(start -0.927 -0.051)
			(end -0.927 -0.351)
			(stroke
				(width 0.15)
				(type solid)
			)
			(layer "F.SilkS")
		)
		(fp_circle
			(center -0.9652 0.9652)
			(end -0.9152 0.9652)
			(stroke
				(width 0.15)
				(type solid)
			)
			(fill yes)
			(layer "F.SilkS")
		)
		(fp_line
			(start 1.1 -1.16)
			(end 1.1 1.15)
			(stroke
				(width 0.05)
				(type solid)
			)
			(layer "F.CrtYd")
		)
		(fp_line
			(start -1.12 -1.16)
			(end 1.1 -1.16)
			(stroke
				(width 0.05)
				(type solid)
			)
			(layer "F.CrtYd")
		)
		(fp_line
			(start -1.12 -1.16)
			(end -1.12 1.15)
			(stroke
				(width 0.05)
				(type solid)
			)
			(layer "F.CrtYd")
		)
		(fp_line
			(start -1.12 1.15)
			(end 1.1 1.15)
			(stroke
				(width 0.05)
				(type solid)
			)
			(layer "F.CrtYd")
		)
		(fp_line
			(start 0.8 -0.425)
			(end -0.652 -0.425)
			(stroke
				(width 0.15)
				(type solid)
			)
			(layer "F.Fab")
		)
		(fp_line
			(start 0.8 -0.425)
			(end 0.8 0.424)
			(stroke
				(width 0.15)
				(type solid)
			)
			(layer "F.Fab")
		)
		(fp_line
			(start -0.652 -0.425)
			(end -0.802 -0.276)
			(stroke
				(width 0.15)
				(type solid)
			)
			(layer "F.Fab")
		)
		(fp_line
			(start -0.802 -0.276)
			(end -0.802 0.424)
			(stroke
				(width 0.15)
				(type solid)
			)
			(layer "F.Fab")
		)
		(fp_line
			(start 0.8 0.424)
			(end -0.802 0.424)
			(stroke
				(width 0.15)
				(type solid)
			)
			(layer "F.Fab")
		)
		(fp_circle
			(center -0.9652 0.9652)
			(end -0.9144 0.9652)
			(stroke
				(width 0.15)
				(type solid)
			)
			(fill no)
			(layer "F.Fab")
		)
		(pad "1" smd rect
			(at -0.5 0.65 90)
			(size 0.4 0.51)
			(layers "F.Cu" "F.Mask" "F.Paste")
			(net 460 "1V8_SYS")
			(pinfunction "G")
			(pintype "bidirectional")
		)
		(pad "2" smd rect
			(at 0.498 0.65 90)
			(size 0.4 0.51)
			(layers "F.Cu" "F.Mask" "F.Paste")
			(net 5 "GND")
			(pinfunction "S")
			(pintype "bidirectional")
		)
		(pad "3" smd rect
			(at 0 -0.652 90)
			(size 0.4 0.51)
			(layers "F.Cu" "F.Mask" "F.Paste")
			(net 235 "Net-(Q9-D)")
			(pinfunction "D")
			(pintype "bidirectional")
		)
	)
	(footprint "antmicro-footprints:C_0805_2012Metric"
		(layer "F.Cu")
		(at 108.9492 112.05 90)
		(descr "Capacitor SMD 0805")
		(tags "capacitor SMD 0805")
		(property "Reference" "C128"
			(at 1.65 0.3508 90)
			(layer "F.SilkS")
			(effects
				(font
					(size 0.7 0.7)
					(thickness 0.15)
				)
				(justify left bottom)
			)
		)
		(property "Value" "C_22u_0805_16V"
			(at 0 1.947 90)
			(layer "F.Fab")
			(effects
				(font
					(size 0.7 0.7)
					(thickness 0.15)
				)
				(justify left bottom)
			)
		)
		(property "Description" " "
			(at 0 0 90)
			(layer "F.Fab")
			(hide yes)
			(effects
				(font
					(size 1.27 1.27)
					(thickness 0.15)
				)
			)
		)
		(property "Author" "Antmicro"
			(at 220.9992 3.1008 0)
			(layer "F.Fab")
			(hide yes)
			(effects
				(font
					(size 1 1)
					(thickness 0.15)
				)
			)
		)
		(property "Dielectric" ""
			(at 220.9992 3.1008 0)
			(layer "F.Fab")
			(hide yes)
			(effects
				(font
					(size 1 1)
					(thickness 0.15)
				)
			)
		)
		(property "License" "Apache-2.0"
			(at 220.9992 3.1008 0)
			(layer "F.Fab")
			(hide yes)
			(effects
				(font
					(size 1 1)
					(thickness 0.15)
				)
			)
		)
		(property "MPN" "GRT21BR61C226ME13L"
			(at 220.9992 3.1008 0)
			(layer "F.Fab")
			(hide yes)
			(effects
				(font
					(size 1 1)
					(thickness 0.15)
				)
			)
		)
		(property "Manufacturer" "Murata"
			(at 220.9992 3.1008 0)
			(layer "F.Fab")
			(hide yes)
			(effects
				(font
					(size 1 1)
					(thickness 0.15)
				)
			)
		)
		(property "Val" "22u/16V"
			(at 220.9992 3.1008 0)
			(layer "F.Fab")
			(hide yes)
			(effects
				(font
					(size 1 1)
					(thickness 0.15)
				)
			)
		)
		(property "Voltage" ""
			(at 220.9992 3.1008 0)
			(layer "F.Fab")
			(hide yes)
			(effects
				(font
					(size 1 1)
					(thickness 0.15)
				)
			)
		)
		(sheetname "Supply")
		(sheetfile "supply.kicad_sch")
		(attr smd)
		(fp_line
			(start -0.3 -0.8)
			(end 0.3 -0.8)
			(stroke
				(width 0.15)
				(type solid)
			)
			(layer "F.SilkS")
		)
		(fp_line
			(start -0.3 0.8)
			(end 0.3 0.8)
			(stroke
				(width 0.15)
				(type solid)
			)
			(layer "F.SilkS")
		)
		(fp_rect
			(start -1.9 -0.93)
			(end 1.9 0.93)
			(stroke
				(width 0.05)
				(type solid)
			)
			(fill no)
			(layer "F.CrtYd")
		)
		(fp_rect
			(start -0.95 -0.675)
			(end 0.95 0.675)
			(stroke
				(width 0.15)
				(type solid)
			)
			(fill no)
			(layer "F.Fab")
		)
		(pad "1" smd rect
			(at -1.05 0 90)
			(size 1.2 1.2)
			(layers "F.Cu" "F.Mask" "F.Paste")
			(net 224 "VIN")
			(pintype "passive")
		)
		(pad "2" smd rect
			(at 1.05 0 90)
			(size 1.2 1.2)
			(layers "F.Cu" "F.Mask" "F.Paste")
			(net 5 "GND")
			(pintype "passive")
		)
	)
	(footprint "antmicro-footprints:C_0603_1608Metric"
		(layer "F.Cu")
		(at 120.0492 113.475 180)
		(descr "Capacitor SMD 0603")
		(tags "capacitor 0603")
		(property "Reference" "C141"
			(at 3.7492 -0.425 180)
			(layer "F.SilkS")
			(effects
				(font
					(size 0.7 0.7)
					(thickness 0.15)
				)
				(justify left bottom)
			)
		)
		(property "Value" "C_47u_0603"
			(at 0 1.6 180)
			(layer "F.Fab")
			(effects
				(font
					(size 0.7 0.7)
					(thickness 0.15)
				)
				(justify left bottom)
			)
		)
		(property "Description" " "
			(at 0 0 180)
			(layer "F.Fab")
			(hide yes)
			(effects
				(font
					(size 1.27 1.27)
					(thickness 0.15)
				)
			)
		)
		(property "Author" "Antmicro"
			(at 240.0984 226.95 0)
			(layer "F.Fab")
			(hide yes)
			(effects
				(font
					(size 1 1)
					(thickness 0.15)
				)
			)
		)
		(property "Dielectric" ""
			(at 240.0984 226.95 0)
			(layer "F.Fab")
			(hide yes)
			(effects
				(font
					(size 1 1)
					(thickness 0.15)
				)
			)
		)
		(property "License" "Apache-2.0"
			(at 240.0984 226.95 0)
			(layer "F.Fab")
			(hide yes)
			(effects
				(font
					(size 1 1)
					(thickness 0.15)
				)
			)
		)
		(property "MPN" "GRM188R60J476ME15D"
			(at 240.0984 226.95 0)
			(layer "F.Fab")
			(hide yes)
			(effects
				(font
					(size 1 1)
					(thickness 0.15)
				)
			)
		)
		(property "Manufacturer" "Murata"
			(at 240.0984 226.95 0)
			(layer "F.Fab")
			(hide yes)
			(effects
				(font
					(size 1 1)
					(thickness 0.15)
				)
			)
		)
		(property "Val" "47u"
			(at 240.0984 226.95 0)
			(layer "F.Fab")
			(hide yes)
			(effects
				(font
					(size 1 1)
					(thickness 0.15)
				)
			)
		)
		(property "Voltage" ""
			(at 240.0984 226.95 0)
			(layer "F.Fab")
			(hide yes)
			(effects
				(font
					(size 1 1)
					(thickness 0.15)
				)
			)
		)
		(sheetname "Supply")
		(sheetfile "supply.kicad_sch")
		(attr smd)
		(fp_line
			(start -0.3 0.3)
			(end 0.3 0.3)
			(stroke
				(width 0.15)
				(type solid)
			)
			(layer "F.SilkS")
		)
		(fp_line
			(start -0.3 -0.3)
			(end 0.3 -0.3)
			(stroke
				(width 0.15)
				(type solid)
			)
			(layer "F.SilkS")
		)
		(fp_rect
			(start -1.24 -0.7)
			(end 1.24 0.7)
			(stroke
				(width 0.05)
				(type solid)
			)
			(fill no)
			(layer "F.CrtYd")
		)
		(fp_rect
			(start -0.8 -0.4)
			(end 0.8 0.4)
			(stroke
				(width 0.15)
				(type solid)
			)
			(fill no)
			(layer "F.Fab")
		)
		(pad "1" smd roundrect
			(at -0.7 0 180)
			(size 0.6 0.8)
			(layers "F.Cu" "F.Mask" "F.Paste")
			(roundrect_rratio 0.2)
			(net 55 "Net-(C141-Pad1)")
			(pintype "passive")
		)
		(pad "2" smd roundrect
			(at 0.7 0 180)
			(size 0.6 0.8)
			(layers "F.Cu" "F.Mask" "F.Paste")
			(roundrect_rratio 0.2)
			(net 5 "GND")
			(pintype "passive")
		)
	)
)
